(kicad_pcb
	(version 20241229)
	(generator "pcbnew")
	(generator_version "9.0")
	(general
		(thickness 1.6642)
		(legacy_teardrops no)
	)
	(paper "A3")
	(title_block
		(title "PolarFire SoM")
		(date "2025-07-22")
		(rev "1.1.4")
		(company "Antmicro Ltd")
		(comment 1 "www.antmicro.com")
		(comment 9 "footprints 126-126 of 470")
	)
	(layers
		(0 "F.Cu" mixed)
		(4 "In1.Cu" power)
		(6 "In2.Cu" signal)
		(8 "In3.Cu" power)
		(10 "In4.Cu" signal)
		(12 "In5.Cu" power)
		(14 "In6.Cu" power)
		(16 "In7.Cu" signal)
		(18 "In8.Cu" power)
		(20 "In9.Cu" signal)
		(22 "In10.Cu" power)
		(24 "In11.Cu" signal)
		(26 "In12.Cu" signal)
		(2 "B.Cu" mixed)
		(9 "F.Adhes" user "F.Adhesive")
		(11 "B.Adhes" user "B.Adhesive")
		(13 "F.Paste" user)
		(15 "B.Paste" user)
		(5 "F.SilkS" user "F.Silkscreen")
		(7 "B.SilkS" user "B.Silkscreen")
		(1 "F.Mask" user)
		(3 "B.Mask" user)
		(17 "Dwgs.User" user "User.Drawings")
		(19 "Cmts.User" user "User.Comments")
		(21 "Eco1.User" user "User.Eco1")
		(23 "Eco2.User" user "User.Eco2")
		(25 "Edge.Cuts" user)
		(27 "Margin" user)
		(31 "F.CrtYd" user "F.Courtyard")
		(29 "B.CrtYd" user "B.Courtyard")
		(35 "F.Fab" user)
		(33 "B.Fab" user)
	)
	(footprint "antmicro-footprints:C_0402_1005Metric"
		(layer "B.Cu")
		(at 186.25 140.65 -90)
		(descr "Capacitor SMD 0402")
		(tags "capacitor SMD 0402")
		(property "Reference" "C218"
			(at -3.725 -0.375 90)
			(layer "B.SilkS")
			(effects
				(font
					(size 0.7 0.7)
					(thickness 0.15)
				)
				(justify left bottom mirror)
			)
		)
		(property "Value" "C_100n_0402"
			(at -1.022927 -2.155213 90)
			(layer "B.Fab")
			(hide yes)
			(effects
				(font
					(size 0.7 0.7)
					(thickness 0.15)
				)
				(justify left bottom mirror)
			)
		)
		(property "Datasheet" "https://www.murata.com/products/productdetail?partno=GRM155R61H104KE14%23"
			(at 0 0 270)
			(layer "F.Fab")
			(hide yes)
			(effects
				(font
					(size 1.27 1.27)
					(thickness 0.15)
				)
			)
		)
		(property "Description" "SMD Multilayer Ceramic Capacitor, 0.1 µF, 50 V, 0402 [1005 Metric], ± 10%, X5R, GRM Series"
			(at 0 0 270)
			(layer "F.Fab")
			(hide yes)
			(effects
				(font
					(size 1.27 1.27)
					(thickness 0.15)
				)
			)
		)
		(property "Author" "Antmicro"
			(at 45.6 326.9 0)
			(layer "B.Fab")
			(hide yes)
			(effects
				(font
					(size 1 1)
					(thickness 0.15)
				)
				(justify mirror)
			)
		)
		(property "Dielectric" "X5R"
			(at 45.6 326.9 0)
			(layer "B.Fab")
			(hide yes)
			(effects
				(font
					(size 1 1)
					(thickness 0.15)
				)
				(justify mirror)
			)
		)
		(property "License" "Apache-2.0"
			(at 45.6 326.9 0)
			(layer "B.Fab")
			(hide yes)
			(effects
				(font
					(size 1 1)
					(thickness 0.15)
				)
				(justify mirror)
			)
		)
		(property "MPN" "GRM155R61H104KE14D"
			(at 45.6 326.9 0)
			(layer "B.Fab")
			(hide yes)
			(effects
				(font
					(size 1 1)
					(thickness 0.15)
				)
				(justify mirror)
			)
		)
		(property "Manufacturer" "Murata"
			(at 45.6 326.9 0)
			(layer "B.Fab")
			(hide yes)
			(effects
				(font
					(size 1 1)
					(thickness 0.15)
				)
				(justify mirror)
			)
		)
		(property "Public" ""
			(at 45.6 326.9 0)
			(layer "B.Fab")
			(hide yes)
			(effects
				(font
					(size 1 1)
					(thickness 0.15)
				)
				(justify mirror)
			)
		)
		(property "Val" "100n"
			(at 45.6 326.9 0)
			(layer "B.Fab")
			(hide yes)
			(effects
				(font
					(size 1 1)
					(thickness 0.15)
				)
				(justify mirror)
			)
		)
		(property "Voltage" "50V"
			(at 45.6 326.9 0)
			(layer "B.Fab")
			(hide yes)
			(effects
				(font
					(size 1 1)
					(thickness 0.15)
				)
				(justify mirror)
			)
		)
		(sheetname "/FPGA GPIO/")
		(sheetfile "fpga-gpio.kicad_sch")
		(attr smd)
		(fp_rect
			(start -0.925 0.47)
			(end 0.925 -0.47)
			(stroke
				(width 0.05)
				(type default)
			)
			(fill no)
			(layer "B.CrtYd")
		)
		(fp_line
			(start -0.494 0.25)
			(end 0.504 0.25)
			(stroke
				(width 0.15)
				(type solid)
			)
			(layer "B.Fab")
		)
		(fp_line
			(start 0.504 0.25)
			(end 0.504 -0.248)
			(stroke
				(width 0.15)
				(type solid)
			)
			(layer "B.Fab")
		)
		(fp_line
			(start -0.494 -0.248)
			(end -0.494 0.25)
			(stroke
				(width 0.15)
				(type solid)
			)
			(layer "B.Fab")
		)
		(fp_line
			(start 0.504 -0.248)
			(end -0.494 -0.248)
			(stroke
				(width 0.15)
				(type solid)
			)
			(layer "B.Fab")
		)
		(fp_text user "License: Apache-2.0"
			(at -0.939 -5.799 90)
			(layer "B.Fab")
			(effects
				(font
					(size 0.7 0.7)
					(thickness 0.15)
				)
				(justify left bottom mirror)
			)
		)
		(fp_text user "${REFERENCE}"
			(at -0.939 -4.599 90)
			(layer "B.Fab")
			(effects
				(font
					(size 0.7 0.7)
					(thickness 0.15)
				)
				(justify left bottom mirror)
			)
		)
		(fp_text user "Author: Antmicro"
			(at -0.939 -3.399 90)
			(layer "B.Fab")
			(effects
				(font
					(size 0.7 0.7)
					(thickness 0.15)
				)
				(justify left bottom mirror)
			)
		)
		(pad "1" smd roundrect
			(at -0.48 0 270)
			(size 0.59 0.64)
			(layers "B.Cu" "B.Mask" "B.Paste")
			(roundrect_rratio 0.25)
			(net 50 "+3V3")
			(pintype "passive")
		)
		(pad "2" smd roundrect
			(at 0.48 0 270)
			(size 0.59 0.64)
			(layers "B.Cu" "B.Mask" "B.Paste")
			(roundrect_rratio 0.25)
			(net 417 "GND")
			(pintype "passive")
		)
	)
)
